FILE_TYPE = CONNECTIVITY;
{Allegro Design Entry HDL 17.2-2016 S081 (4005846) 1/11/2022}
"PAGE_NUMBER" = 186;
0"NC";
1"P3V3_AUX\g";
2"P3V3_AUX\g";
3"P3V3_AUX\g";
4"P3V3_AUX\g";
5"P3V3_AUX\g";
6"P3V3_AUX\g";
7"P3V3_AUX\g";
8"P3V3_AUX\g";
9"GND\g";
10"GND\g";
11"GND\g";
12"GND\g";
13"GND\g";
14"GND\g";
15"GND\g";
16"FM_PCH_CONSENT_STRAP_N";
17"FM_ADR_ACK";
18"FM_PCH_SPKR";
19"FM_PCH_BOOT_BIOS_STRAP";
20"FM_ADR_MODE0";
21"FM_FLASH_SECURITY_STRAP";
22"FM_ADR_MODE1";
23"FM_SPI_3V3_1V8_VOLTAGE";
%"UNIVERSAL_POWER"
"1","(-3475,1525)","0","logical_power","I10";
;
HDL_POWER"P3V3_AUX"
CDS_LIB"logical_power";
"A"1;
%"Q_RES"
"2","(-3475,1275)","0","pure_quanta","I11";
;
PART_NUMBER"CS21002FB06"
WATTAGE"1/16W"
MATERIAL"EMPTY"
PACK_TYPE"0402LF"
VALUE"1K"
TOLERANCE"1%"
$LOCATION"R367"
CDS_LIB"pure_quanta"
CDS_LOCATION"R367"
$SEC"1"
CDS_SEC"1";
"A"
$PN"1"1;
"B"
$PN"2"18;
%"UNIVERSAL_POWER"
"1","(-3475,-550)","0","logical_power","I15";
;
HDL_POWER"P3V3_AUX"
CDS_LIB"logical_power";
"A"2;
%"Q_RES"
"2","(-3475,-800)","0","pure_quanta","I16";
;
PART_NUMBER"CS21002FB06"
TOLERANCE"1%"
MATERIAL"CHIP"
PACK_TYPE"0402LF"
WATTAGE"1/16W"
VALUE"1K"
$LOCATION"R369"
CDS_LIB"pure_quanta"
CDS_LOCATION"R369"
$SEC"1"
CDS_SEC"1";
"A"
$PN"1"2;
"B"
$PN"2"17;
%"UNIVERSAL_POWER"
"1","(-350,3550)","0","logical_power","I44";
;
HDL_POWER"P3V3_AUX"
CDS_LIB"logical_power";
"A"3;
%"Q_RES"
"2","(-350,3300)","0","pure_quanta","I45";
;
PART_NUMBER"CS21002FB06"
TOLERANCE"1%"
VALUE"1K"
MATERIAL"EMPTY"
WATTAGE"1/16W"
PACK_TYPE"0402LF"
$LOCATION"R371"
CDS_LIB"pure_quanta"
CDS_LOCATION"R371"
$SEC"1"
CDS_SEC"1";
"A"
$PN"1"3;
"B"
$PN"2"19;
%"Q_RES"
"2","(-350,2775)","0","pure_quanta","I46";
;
PART_NUMBER"CS31002FB08"
WATTAGE"1/16W"
TOLERANCE"1%"
PACK_TYPE"0402LF"
VALUE"10K"
MATERIAL"CHIP"
$LOCATION"R372"
CDS_LIB"pure_quanta"
CDS_LOCATION"R372"
$SEC"1"
CDS_SEC"1";
"A"
$PN"1"19;
"B"
$PN"2"14;
%"UNIVERSAL_GND"
"1","(-350,2550)","0","logical_power","I47";
;
ROOM"IO_SLOT"
HDL_POWER"GND"
CDS_LIB"logical_power";
"A"14;
%"UNIVERSAL_POWER"
"1","(-350,-550)","0","logical_power","I58";
;
HDL_POWER"P3V3_AUX"
CDS_LIB"logical_power";
"A"4;
%"Q_RES"
"2","(-350,-800)","0","pure_quanta","I60";
;
PART_NUMBER"CS21002FB06"
TOLERANCE"1%"
VALUE"1K"
WATTAGE"1/16W"
PACK_TYPE"0402LF"
MATERIAL"EMPTY"
$LOCATION"R374"
CDS_LIB"pure_quanta"
CDS_LOCATION"R374"
$SEC"1"
CDS_SEC"1";
"A"
$PN"1"4;
"B"
$PN"2"23;
%"Q_RES"
"2","(-350,-1275)","0","pure_quanta","I61";
;
PART_NUMBER"CS31002FB08"
VALUE"10K"
WATTAGE"1/16W"
MATERIAL"CHIP"
PACK_TYPE"0402LF"
TOLERANCE"1%"
$LOCATION"R375"
CDS_LIB"pure_quanta"
CDS_LOCATION"R375"
$SEC"1"
CDS_SEC"1";
"A"
$PN"1"23;
"B"
$PN"2"9;
%"UNIVERSAL_GND"
"1","(-350,-1500)","0","logical_power","I62";
;
ROOM"IO_SLOT"
HDL_POWER"GND"
CDS_LIB"logical_power";
"A"9;
%"UNIVERSAL_POWER"
"1","(2825,3500)","0","logical_power","I65";
;
HDL_POWER"P3V3_AUX"
CDS_LIB"logical_power";
"A"8;
%"Q_RES"
"2","(2825,3250)","0","pure_quanta","I68";
;
PART_NUMBER"CS32002FB06"
MATERIAL"CHIP"
WATTAGE"1/16W"
VALUE"20K"
PACK_TYPE"0402LF"
TOLERANCE"1%"
$LOCATION"R502"
CDS_LIB"pure_quanta"
CDS_LOCATION"R502"
$SEC"1"
CDS_SEC"1";
"A"
$PN"1"8;
"B"
$PN"2"16;
%"UNIVERSAL_POWER"
"1","(2800,1500)","0","logical_power","I73";
;
HDL_POWER"P3V3_AUX"
CDS_LIB"logical_power";
"A"5;
%"UNIVERSAL_GND"
"1","(2800,550)","0","logical_power","I74";
;
ROOM"IO_SLOT"
HDL_POWER"GND"
CDS_LIB"logical_power";
"A"10;
%"Q_RES"
"2","(2800,775)","0","pure_quanta","I76";
;
PART_NUMBER"CS21002FB06"
TOLERANCE"1%"
VALUE"1K"
WATTAGE"1/16W"
MATERIAL"CHIP"
PACK_TYPE"0402LF"
$LOCATION"R379"
CDS_LIB"pure_quanta"
CDS_LOCATION"R379"
$SEC"1"
CDS_SEC"1";
"A"
$PN"1"22;
"B"
$PN"2"10;
%"Q_RES"
"2","(2800,1250)","0","pure_quanta","I77";
;
PART_NUMBER"CS21002FB06"
TOLERANCE"1%"
VALUE"1K"
WATTAGE"1/16W"
MATERIAL"EMPTY"
PACK_TYPE"0402LF"
$LOCATION"R378"
CDS_LIB"pure_quanta"
CDS_LOCATION"R378"
$SEC"1"
CDS_SEC"1";
"A"
$PN"1"5;
"B"
$PN"2"22;
%"Q_RES"
"2","(2800,-775)","0","pure_quanta","I78";
;
PART_NUMBER"CS21002FB06"
TOLERANCE"1%"
PACK_TYPE"0402LF"
MATERIAL"EMPTY"
VALUE"1K"
WATTAGE"1/16W"
$LOCATION"R380"
CDS_LIB"pure_quanta"
CDS_LOCATION"R380"
$SEC"1"
CDS_SEC"1";
"A"
$PN"1"6;
"B"
$PN"2"21;
%"UNIVERSAL_POWER"
"1","(2800,-525)","0","logical_power","I80";
;
HDL_POWER"P3V3_AUX"
CDS_LIB"logical_power";
"A"6;
%"Q_RES"
"2","(2800,-1300)","0","pure_quanta","I81";
;
PART_NUMBER"CS31002FB08"
VALUE"10K"
PACK_TYPE"0402LF"
MATERIAL"CHIP"
WATTAGE"1/16W"
TOLERANCE"1%"
$LOCATION"R381"
CDS_LIB"pure_quanta"
CDS_LOCATION"R381"
$SEC"1"
CDS_SEC"1";
"A"
$PN"1"21;
"B"
$PN"2"11;
%"UNIVERSAL_GND"
"1","(2800,-1525)","0","logical_power","I82";
;
ROOM"IO_SLOT"
HDL_POWER"GND"
CDS_LIB"logical_power";
"A"11;
%"UNIVERSAL_POWER"
"1","(-3450,3550)","0","logical_power","I85";
;
HDL_POWER"P3V3_AUX"
CDS_LIB"logical_power";
"A"7;
%"UNIVERSAL_GND"
"1","(-3450,2550)","0","logical_power","I87";
;
ROOM"IO_SLOT"
HDL_POWER"GND"
CDS_LIB"logical_power";
"A"12;
%"Q_RES"
"2","(-3450,2775)","0","pure_quanta","I88";
;
PART_NUMBER"CS21002FB06"
MATERIAL"EMPTY"
TOLERANCE"1%"
PACK_TYPE"0402LF"
WATTAGE"1/16W"
VALUE"1K"
$LOCATION"R1810"
CDS_LIB"pure_quanta"
CDS_LOCATION"R1810"
$SEC"1"
CDS_SEC"1";
"A"
$PN"1"20;
"B"
$PN"2"12;
%"Q_RES"
"2","(-3450,3300)","0","pure_quanta","I89";
;
PART_NUMBER"CS32002FB06"
VALUE"20K"
PACK_TYPE"0402LF"
MATERIAL"CHIP"
WATTAGE"1/16W"
TOLERANCE"1%"
$LOCATION"R1809"
CDS_LIB"pure_quanta"
CDS_LOCATION"R1809"
$SEC"1"
CDS_SEC"1";
"A"
$PN"1"7;
"B"
$PN"2"20;
%"Q_RES"
"2","(2825,2800)","0","pure_quanta","I90";
;
PART_NUMBER"CS32002FB06"
MATERIAL"EMPTY"
WATTAGE"1/16W"
TOLERANCE"1%"
VALUE"20K"
PACK_TYPE"0402LF"
$LOCATION"R1962"
CDS_LIB"pure_quanta"
CDS_LOCATION"R1962"
$SEC"1"
CDS_SEC"1";
"A"
$PN"1"16;
"B"
$PN"2"13;
%"UNIVERSAL_GND"
"1","(2825,2575)","0","logical_power","I91";
;
ROOM"IO_SLOT"
HDL_POWER"GND"
CDS_LIB"logical_power";
"A"13;
%"Q_RES"
"2","(-3475,775)","0","pure_quanta","I92";
;
PART_NUMBER"CS31002FB08"
PACK_TYPE"0402LF"
WATTAGE"1/16W"
MATERIAL"CHIP"
VALUE"10K"
TOLERANCE"1%"
$LOCATION"R3325"
CDS_LIB"pure_quanta"
CDS_LOCATION"R3325"
$SEC"1"
CDS_SEC"1";
"A"
$PN"1"18;
"B"
$PN"2"15;
%"UNIVERSAL_GND"
"1","(-3475,550)","0","logical_power","I93";
;
ROOM"IO_SLOT"
HDL_POWER"GND"
CDS_LIB"logical_power";
"A"15;
END.
